# BASEBOARD_FAB2 (Tioga Pass) — schematic netlist excerpt (pin names and nets, part order shuffled) for the footprints in the layout excerpt that follows; sources: Cadence DE-HDL packaged netlist, KiCad conversion of Wiwynn_Tioga_Pass_MB.brd

R3T3  RES  4.75K 1% EMPTY  pkg 0402  page 153 : A = P3V3_STBY ; B = PU_SPI1_RST
R25W180  RES  1.00K 1% CHIP  pkg 0402  page 255 : A = P3V3_STBY ; B = BMC_DEBUG_EN_N
R6L14  RES  2 1.0% CHIP  pkg 0402  page 98 : A = M_E_CPU_VREF ; B = M_E_VREF

(kicad_pcb
	(version 20260206)
	(generator "pcbnew")
	(generator_version "10.0")
	(general
		(thickness 1.6)
		(legacy_teardrops no)
	)
	(paper "A4")
	(title_block
		(title "Wiwynn_Tioga_Pass_MB.brd")
		(comment 1 "Tioga Pass / footprints 3267-3269 of 4770")
	)
	(layers
		(0 "F.Cu" signal "TOP")
		(4 "In1.Cu" signal "L2GND")
		(6 "In2.Cu" signal "L3")
		(8 "In3.Cu" signal "L4GND")
		(10 "In4.Cu" signal "L5")
		(12 "In5.Cu" signal "L6GND")
		(14 "In6.Cu" signal "L7VCC")
		(16 "In7.Cu" signal "L8VCC")
		(18 "In8.Cu" signal "L9GND")
		(20 "In9.Cu" signal "L10")
		(22 "In10.Cu" signal "L11GND")
		(24 "In11.Cu" signal "L12")
		(26 "In12.Cu" signal "L13GND")
		(2 "B.Cu" signal "BOTTOM")
		(9 "F.Adhes" user "F.Adhesive")
		(11 "B.Adhes" user "B.Adhesive")
		(13 "F.Paste" user "Package Geometry/Pastemask Top")
		(15 "B.Paste" user "Package Geometry/Pastemask Bottom")
		(5 "F.SilkS" user "Ref Des/Silkscreen Top")
		(7 "B.SilkS" user "Ref Des/Silkscreen Bottom")
		(1 "F.Mask" user "Board Geometry/Soldermask Top")
		(3 "B.Mask" user "Board Geometry/Soldermask Bottom")
		(17 "Dwgs.User" user "User.Drawings")
		(19 "Cmts.User" user "User.Comments")
		(21 "Eco1.User" user "User.Eco1")
		(23 "Eco2.User" user "User.Eco2")
		(25 "Edge.Cuts" user "Board Geometry/Outline")
		(27 "Margin" user)
		(31 "F.CrtYd" user "Package Geometry/Place Bound Top")
		(29 "B.CrtYd" user "Package Geometry/Place Bound Bottom")
		(35 "F.Fab" user "Ref Des/Assembly Top")
		(33 "B.Fab" user "Ref Des/Assembly Bottom")
	)
	(footprint ""
		(layer "B.Cu")
		(at 400.31416 -54.25186)
		(property "Reference" "R3T3"
			(at 0 0 0)
			(layer "B.SilkS")
			(hide yes)
			(effects
				(font
					(size 1.27 1.27)
				)
				(justify mirror)
			)
		)
		(property "Value" ""
			(at 0 0 0)
			(layer "B.Fab")
			(effects
				(font
					(size 1.27 1.27)
				)
				(justify mirror)
			)
		)
		(duplicate_pad_numbers_are_jumpers no)
		(fp_poly
			(pts
				(xy 0.2794 -0.1016) (xy -0.2794 -0.1016) (xy -0.2794 0.9906) (xy 0.2794 0.9906)
			)
			(stroke
				(width 0)
				(type default)
			)
			(fill no)
			(layer "B.CrtYd")
		)
		(fp_line
			(start -0.2794 -0.1016)
			(end 0.2794 -0.1016)
			(stroke
				(width 0.1)
				(type default)
			)
			(layer "B.Fab")
		)
		(fp_line
			(start -0.2794 0.9906)
			(end -0.2794 -0.1016)
			(stroke
				(width 0.1)
				(type default)
			)
			(layer "B.Fab")
		)
		(fp_line
			(start 0.2794 -0.1016)
			(end 0.2794 0.9906)
			(stroke
				(width 0.1)
				(type default)
			)
			(layer "B.Fab")
		)
		(fp_line
			(start 0.2794 0.9906)
			(end -0.2794 0.9906)
			(stroke
				(width 0.1)
				(type default)
			)
			(layer "B.Fab")
		)
		(pad "1" smd rect
			(at 0 0 180)
			(size 0.508 0.508)
			(layers "B.Cu" "B.Mask" "B.Paste")
			(net "P3V3_STBY")
		)
		(pad "2" smd rect
			(at 0 0.889 180)
			(size 0.508 0.508)
			(layers "B.Cu" "B.Mask" "B.Paste")
			(net "PU_SPI1_RST")
		)
		(zone
			(layer "B.Cu")
			(hatch none 0.5)
			(connect_pads
				(clearance 0)
			)
			(min_thickness 0.25)
			(keepout
				(tracks allowed)
				(vias not_allowed)
				(pads allowed)
				(copperpour not_allowed)
				(footprints allowed)
			)
			(placement
				(enabled no)
				(sheetname "")
			)
			(fill
				(thermal_gap 0.5)
				(thermal_bridge_width 0.5)
				(island_removal_mode 0)
			)
			(polygon
				(pts
					(xy 400.56816 -53.99786) (xy 400.06016 -53.99786) (xy 400.06016 -53.61686) (xy 400.56816 -53.61686)
				)
			)
		)
		(zone
			(layer "B.Cu")
			(hatch none 0.5)
			(connect_pads
				(clearance 0)
			)
			(min_thickness 0.25)
			(keepout
				(tracks not_allowed)
				(vias allowed)
				(pads allowed)
				(copperpour not_allowed)
				(footprints allowed)
			)
			(placement
				(enabled no)
				(sheetname "")
			)
			(fill
				(thermal_gap 0.5)
				(thermal_bridge_width 0.5)
				(island_removal_mode 0)
			)
			(polygon
				(pts
					(xy 400.56816 -53.61686) (xy 400.06016 -53.61686) (xy 400.06016 -53.99786) (xy 400.56816 -53.99786)
				)
			)
		)
	)
	(footprint ""
		(layer "B.Cu")
		(at 192.659 -144.4752 180)
		(property "Reference" "R6L14"
			(at 0 0 0)
			(layer "B.SilkS")
			(hide yes)
			(effects
				(font
					(size 1.27 1.27)
				)
				(justify mirror)
			)
		)
		(property "Value" ""
			(at 0 0 0)
			(layer "B.Fab")
			(effects
				(font
					(size 1.27 1.27)
				)
				(justify mirror)
			)
		)
		(duplicate_pad_numbers_are_jumpers no)
		(fp_poly
			(pts
				(xy 0.2794 -0.1016) (xy -0.2794 -0.1016) (xy -0.2794 0.9906) (xy 0.2794 0.9906)
			)
			(stroke
				(width 0)
				(type default)
			)
			(fill no)
			(layer "B.CrtYd")
		)
		(fp_line
			(start 0.2794 0.9906)
			(end -0.2794 0.9906)
			(stroke
				(width 0.1)
				(type default)
			)
			(layer "B.Fab")
		)
		(fp_line
			(start 0.2794 -0.1016)
			(end 0.2794 0.9906)
			(stroke
				(width 0.1)
				(type default)
			)
			(layer "B.Fab")
		)
		(fp_line
			(start -0.2794 0.9906)
			(end -0.2794 -0.1016)
			(stroke
				(width 0.1)
				(type default)
			)
			(layer "B.Fab")
		)
		(fp_line
			(start -0.2794 -0.1016)
			(end 0.2794 -0.1016)
			(stroke
				(width 0.1)
				(type default)
			)
			(layer "B.Fab")
		)
		(pad "1" smd rect
			(at 0 0)
			(size 0.508 0.508)
			(layers "B.Cu" "B.Mask" "B.Paste")
			(net "M_E_CPU_VREF")
		)
		(pad "2" smd rect
			(at 0 0.889)
			(size 0.508 0.508)
			(layers "B.Cu" "B.Mask" "B.Paste")
			(net "M_E_VREF")
		)
		(zone
			(layer "B.Cu")
			(hatch none 0.5)
			(connect_pads
				(clearance 0)
			)
			(min_thickness 0.25)
			(keepout
				(tracks not_allowed)
				(vias allowed)
				(pads allowed)
				(copperpour not_allowed)
				(footprints allowed)
			)
			(placement
				(enabled no)
				(sheetname "")
			)
			(fill
				(thermal_gap 0.5)
				(thermal_bridge_width 0.5)
				(island_removal_mode 0)
			)
			(polygon
				(pts
					(xy 192.405 -145.1102) (xy 192.913 -145.1102) (xy 192.913 -144.7292) (xy 192.405 -144.7292)
				)
			)
		)
		(zone
			(layer "B.Cu")
			(hatch none 0.5)
			(connect_pads
				(clearance 0)
			)
			(min_thickness 0.25)
			(keepout
				(tracks allowed)
				(vias not_allowed)
				(pads allowed)
				(copperpour not_allowed)
				(footprints allowed)
			)
			(placement
				(enabled no)
				(sheetname "")
			)
			(fill
				(thermal_gap 0.5)
				(thermal_bridge_width 0.5)
				(island_removal_mode 0)
			)
			(polygon
				(pts
					(xy 192.405 -144.7292) (xy 192.913 -144.7292) (xy 192.913 -145.1102) (xy 192.405 -145.1102)
				)
			)
		)
	)
	(footprint ""
		(layer "B.Cu")
		(at 442.669168 -146.875754 90)
		(property "Reference" "R25W180"
			(at 0.8382 -0.67818 90)
			(unlocked yes)
			(layer "B.SilkS")
			(effects
				(font
					(size 0.4064 0.254)
					(thickness 0.1524)
				)
				(justify left mirror)
			)
		)
		(property "Value" ""
			(at 0 0 90)
			(layer "B.Fab")
			(effects
				(font
					(size 1.27 1.27)
				)
				(justify mirror)
			)
		)
		(duplicate_pad_numbers_are_jumpers no)
		(fp_poly
			(pts
				(xy 0.2794 -0.1016) (xy -0.2794 -0.1016) (xy -0.2794 0.9906) (xy 0.2794 0.9906)
			)
			(stroke
				(width 0)
				(type default)
			)
			(fill no)
			(layer "B.CrtYd")
		)
		(fp_line
			(start 0.2794 -0.1016)
			(end 0.2794 0.9906)
			(stroke
				(width 0.1)
				(type default)
			)
			(layer "B.Fab")
		)
		(fp_line
			(start -0.2794 -0.1016)
			(end 0.2794 -0.1016)
			(stroke
				(width 0.1)
				(type default)
			)
			(layer "B.Fab")
		)
		(fp_line
			(start 0.2794 0.9906)
			(end -0.2794 0.9906)
			(stroke
				(width 0.1)
				(type default)
			)
			(layer "B.Fab")
		)
		(fp_line
			(start -0.2794 0.9906)
			(end -0.2794 -0.1016)
			(stroke
				(width 0.1)
				(type default)
			)
			(layer "B.Fab")
		)
		(pad "1" smd rect
			(at 0 0 270)
			(size 0.508 0.508)
			(layers "B.Cu" "B.Mask" "B.Paste")
			(net "P3V3_STBY")
		)
		(pad "2" smd rect
			(at 0 0.889 270)
			(size 0.508 0.508)
			(layers "B.Cu" "B.Mask" "B.Paste")
			(net "BMC_DEBUG_EN_N")
		)
		(zone
			(layer "B.Cu")
			(hatch none 0.5)
			(connect_pads
				(clearance 0)
			)
			(min_thickness 0.25)
			(keepout
				(tracks allowed)
				(vias not_allowed)
				(pads allowed)
				(copperpour not_allowed)
				(footprints allowed)
			)
			(placement
				(enabled no)
				(sheetname "")
			)
			(fill
				(thermal_gap 0.5)
				(thermal_bridge_width 0.5)
				(island_removal_mode 0)
			)
			(polygon
				(pts
					(xy 442.923168 -147.129754) (xy 442.923168 -146.621754) (xy 443.304168 -146.621754) (xy 443.304168 -147.129754)
				)
			)
		)
		(zone
			(layer "B.Cu")
			(hatch none 0.5)
			(connect_pads
				(clearance 0)
			)
			(min_thickness 0.25)
			(keepout
				(tracks not_allowed)
				(vias allowed)
				(pads allowed)
				(copperpour not_allowed)
				(footprints allowed)
			)
			(placement
				(enabled no)
				(sheetname "")
			)
			(fill
				(thermal_gap 0.5)
				(thermal_bridge_width 0.5)
				(island_removal_mode 0)
			)
			(polygon
				(pts
					(xy 443.304168 -147.129754) (xy 443.304168 -146.621754) (xy 442.923168 -146.621754) (xy 442.923168 -147.129754)
				)
			)
		)
	)
)
